(kicad_pcb
	(version 20260206)
	(generator "pcbnew")
	(generator_version "10.0")
	(general
		(thickness 1.6)
		(legacy_teardrops no)
	)
	(paper "A4")
	(title_block
		(title "03242023_DA0F0TMBIJ0_F0T_Motherboard_J_brd_V01_OCP.brd")
		(comment 1 "Grand Teton / footprints 5252-5258 of 6105")
	)
	(layers
		(0 "F.Cu" signal "TOP")
		(4 "In1.Cu" signal "GND")
		(6 "In2.Cu" signal "IN1")
		(8 "In3.Cu" signal "GND1")
		(10 "In4.Cu" signal "IN2")
		(12 "In5.Cu" signal "GND2")
		(14 "In6.Cu" signal "IN3")
		(16 "In7.Cu" signal "GND3")
		(18 "In8.Cu" signal "VCC")
		(20 "In9.Cu" signal "VCC1")
		(22 "In10.Cu" signal "GND4")
		(24 "In11.Cu" signal "IN4")
		(26 "In12.Cu" signal "GND5")
		(28 "In13.Cu" signal "IN5")
		(30 "In14.Cu" signal "GND6")
		(32 "In15.Cu" signal "IN6")
		(34 "In16.Cu" signal "GND7")
		(2 "B.Cu" signal "BOTTOM")
		(9 "F.Adhes" user "F.Adhesive")
		(11 "B.Adhes" user "B.Adhesive")
		(13 "F.Paste" user "Package Geometry/Pastemask Top")
		(15 "B.Paste" user "Package Geometry/Pastemask Bottom")
		(5 "F.SilkS" user "Ref Des/Silkscreen Top")
		(7 "B.SilkS" user "Ref Des/Silkscreen Bottom")
		(1 "F.Mask" user "Board Geometry/Soldermask Top")
		(3 "B.Mask" user "Board Geometry/Soldermask Bottom")
		(17 "Dwgs.User" user "User.Drawings")
		(19 "Cmts.User" user "User.Comments")
		(21 "Eco1.User" user "User.Eco1")
		(23 "Eco2.User" user "User.Eco2")
		(25 "Edge.Cuts" user "Board Geometry/Outline")
		(27 "Margin" user)
		(31 "F.CrtYd" user "Package Geometry/Place Bound Top")
		(29 "B.CrtYd" user "Package Geometry/Place Bound Bottom")
		(35 "F.Fab" user "Ref Des/Assembly Top")
		(33 "B.Fab" user "Ref Des/Assembly Bottom")
	)
	(footprint ""
		(layer "B.Cu")
		(at 277.138384 -193.669666 -90)
		(property "Reference" "R249"
			(at 0 0 90)
			(layer "B.SilkS")
			(hide yes)
			(effects
				(font
					(size 1.27 1.27)
				)
				(justify mirror)
			)
		)
		(property "Value" ""
			(at 0 0 90)
			(layer "B.Fab")
			(effects
				(font
					(size 1.27 1.27)
				)
				(justify mirror)
			)
		)
		(duplicate_pad_numbers_are_jumpers no)
		(fp_line
			(start -0.7874 0.4064)
			(end 0.7874 0.4064)
			(stroke
				(width 0.1524)
				(type default)
			)
			(layer "B.SilkS")
		)
		(fp_line
			(start 0.7874 0.4064)
			(end 0.7874 -0.4064)
			(stroke
				(width 0.1524)
				(type default)
			)
			(layer "B.SilkS")
		)
		(fp_line
			(start -0.7874 -0.4064)
			(end -0.7874 0.4064)
			(stroke
				(width 0.1524)
				(type default)
			)
			(layer "B.SilkS")
		)
		(fp_line
			(start 0.7874 -0.4064)
			(end -0.7874 -0.4064)
			(stroke
				(width 0.1524)
				(type default)
			)
			(layer "B.SilkS")
		)
		(fp_line
			(start -0.67945 0.3048)
			(end -0.120396 0.3048)
			(stroke
				(width 0.1)
				(type default)
			)
			(layer "B.Fab")
		)
		(fp_line
			(start -0.120396 0.3048)
			(end -0.120396 0.2794)
			(stroke
				(width 0.1)
				(type default)
			)
			(layer "B.Fab")
		)
		(fp_line
			(start 0.12065 0.3048)
			(end 0.67945 0.3048)
			(stroke
				(width 0.1)
				(type default)
			)
			(layer "B.Fab")
		)
		(fp_line
			(start 0.67945 0.3048)
			(end 0.67945 -0.305054)
			(stroke
				(width 0.1)
				(type default)
			)
			(layer "B.Fab")
		)
		(fp_line
			(start -0.120396 0.2794)
			(end 0.12065 0.2794)
			(stroke
				(width 0.1)
				(type default)
			)
			(layer "B.Fab")
		)
		(fp_line
			(start 0.12065 0.2794)
			(end 0.12065 0.3048)
			(stroke
				(width 0.1)
				(type default)
			)
			(layer "B.Fab")
		)
		(fp_line
			(start -0.12065 -0.2794)
			(end -0.12065 -0.3048)
			(stroke
				(width 0.1)
				(type default)
			)
			(layer "B.Fab")
		)
		(fp_line
			(start 0.12065 -0.2794)
			(end -0.12065 -0.2794)
			(stroke
				(width 0.1)
				(type default)
			)
			(layer "B.Fab")
		)
		(fp_line
			(start -0.67945 -0.3048)
			(end -0.67945 0.3048)
			(stroke
				(width 0.1)
				(type default)
			)
			(layer "B.Fab")
		)
		(fp_line
			(start -0.12065 -0.3048)
			(end -0.67945 -0.3048)
			(stroke
				(width 0.1)
				(type default)
			)
			(layer "B.Fab")
		)
		(fp_line
			(start 0.12065 -0.305054)
			(end 0.12065 -0.2794)
			(stroke
				(width 0.1)
				(type default)
			)
			(layer "B.Fab")
		)
		(fp_line
			(start 0.67945 -0.305054)
			(end 0.12065 -0.305054)
			(stroke
				(width 0.1)
				(type default)
			)
			(layer "B.Fab")
		)
		(pad "1" smd circle
			(at 0.40005 0 90)
			(size 0 0)
			(layers "B.Cu" "B.Mask" "B.Paste")
			(net "PVNN_TERM_CPU0")
		)
		(pad "2" smd circle
			(at -0.40005 0 90)
			(size 0 0)
			(layers "B.Cu" "B.Mask" "B.Paste")
			(net "FM_S3M_CPU0_LVC1_GPIO_0")
		)
	)
	(footprint ""
		(layer "B.Cu")
		(at 54.880002 -151.098758 180)
		(property "Reference" "PC449_P1_2"
			(at 0 0 0)
			(layer "B.SilkS")
			(hide yes)
			(effects
				(font
					(size 1.27 1.27)
				)
				(justify mirror)
			)
		)
		(property "Value" ""
			(at 0 0 0)
			(layer "B.Fab")
			(effects
				(font
					(size 1.27 1.27)
				)
				(justify mirror)
			)
		)
		(duplicate_pad_numbers_are_jumpers no)
		(fp_line
			(start 1.524 0.762)
			(end 1.524 -0.762)
			(stroke
				(width 0.1524)
				(type default)
			)
			(layer "B.SilkS")
		)
		(fp_line
			(start 1.524 -0.762)
			(end -1.524 -0.762)
			(stroke
				(width 0.1524)
				(type default)
			)
			(layer "B.SilkS")
		)
		(fp_line
			(start -1.524 0.762)
			(end 1.524 0.762)
			(stroke
				(width 0.1524)
				(type default)
			)
			(layer "B.SilkS")
		)
		(fp_line
			(start -1.524 -0.762)
			(end -1.524 0.762)
			(stroke
				(width 0.1524)
				(type default)
			)
			(layer "B.SilkS")
		)
		(fp_line
			(start 1.1049 0.724916)
			(end -1.1049 0.724916)
			(stroke
				(width 0.1)
				(type default)
			)
			(layer "B.Fab")
		)
		(fp_line
			(start 1.1049 -0.724916)
			(end 1.1049 0.724916)
			(stroke
				(width 0.1)
				(type default)
			)
			(layer "B.Fab")
		)
		(fp_line
			(start -1.1049 0.724916)
			(end -1.1049 -0.724916)
			(stroke
				(width 0.1)
				(type default)
			)
			(layer "B.Fab")
		)
		(fp_line
			(start -1.1049 -0.724916)
			(end 1.1049 -0.724916)
			(stroke
				(width 0.1)
				(type default)
			)
			(layer "B.Fab")
		)
		(pad "1" smd rect
			(at 0.889 0 180)
			(size 1.016 1.27)
			(layers "B.Cu" "B.Mask" "B.Paste")
			(net "SW_P12V_PVCCINFAON_CPU1_FLT")
		)
		(pad "2" smd rect
			(at -0.889 0 180)
			(size 1.016 1.27)
			(layers "B.Cu" "B.Mask" "B.Paste")
			(net "GND")
		)
	)
	(footprint ""
		(layer "B.Cu")
		(at 362.762038 -337.564984 -90)
		(property "Reference" "PC285_P0_3"
			(at 0 0 90)
			(layer "B.SilkS")
			(hide yes)
			(effects
				(font
					(size 1.27 1.27)
				)
				(justify mirror)
			)
		)
		(property "Value" ""
			(at 0 0 90)
			(layer "B.Fab")
			(effects
				(font
					(size 1.27 1.27)
				)
				(justify mirror)
			)
		)
		(duplicate_pad_numbers_are_jumpers no)
		(fp_line
			(start -1.524 0.762)
			(end 1.524 0.762)
			(stroke
				(width 0.1524)
				(type default)
			)
			(layer "B.SilkS")
		)
		(fp_line
			(start 1.524 0.762)
			(end 1.524 -0.762)
			(stroke
				(width 0.1524)
				(type default)
			)
			(layer "B.SilkS")
		)
		(fp_line
			(start -1.524 -0.762)
			(end -1.524 0.762)
			(stroke
				(width 0.1524)
				(type default)
			)
			(layer "B.SilkS")
		)
		(fp_line
			(start 1.524 -0.762)
			(end -1.524 -0.762)
			(stroke
				(width 0.1524)
				(type default)
			)
			(layer "B.SilkS")
		)
		(fp_line
			(start -1.1049 0.724916)
			(end -1.1049 -0.724916)
			(stroke
				(width 0.1)
				(type default)
			)
			(layer "B.Fab")
		)
		(fp_line
			(start 1.1049 0.724916)
			(end -1.1049 0.724916)
			(stroke
				(width 0.1)
				(type default)
			)
			(layer "B.Fab")
		)
		(fp_line
			(start -1.1049 -0.724916)
			(end 1.1049 -0.724916)
			(stroke
				(width 0.1)
				(type default)
			)
			(layer "B.Fab")
		)
		(fp_line
			(start 1.1049 -0.724916)
			(end 1.1049 0.724916)
			(stroke
				(width 0.1)
				(type default)
			)
			(layer "B.Fab")
		)
		(pad "1" smd rect
			(at 0.889 0 270)
			(size 1.016 1.27)
			(layers "B.Cu" "B.Mask" "B.Paste")
			(net "SW_P12V_PVCCIN_CPU0_FLT")
		)
		(pad "2" smd rect
			(at -0.889 0 270)
			(size 1.016 1.27)
			(layers "B.Cu" "B.Mask" "B.Paste")
			(net "GND")
		)
	)
	(footprint ""
		(layer "B.Cu")
		(at 509.384808 -153.16708 90)
		(property "Reference" "X25"
			(at 1.517142 2.940558 270)
			(unlocked yes)
			(layer "B.SilkS")
			(effects
				(font
					(size 0.7874 0.5842)
					(thickness 0.1524)
				)
				(justify left mirror)
			)
		)
		(property "Value" ""
			(at 0 0 90)
			(layer "B.Fab")
			(effects
				(font
					(size 1.27 1.27)
				)
				(justify mirror)
			)
		)
		(property "Device Type" "TP_TDR_4P_FTS_TH-TP_TDR_4P_DIPA"
			(at -1.30175 1.27 0)
			(unlocked yes)
			(layer "B.Fab")
			(hide yes)
			(effects
				(font
					(size 0.635 0.4064)
					(thickness 0.1524)
				)
				(justify mirror)
			)
		)
		(property "User Part Number" "N_A"
			(at -1.30175 1.27 0)
			(unlocked yes)
			(layer "Cmts.User")
			(hide yes)
			(effects
				(font
					(size 0.635 0.4064)
					(thickness 0.1524)
				)
				(justify mirror)
			)
		)
		(duplicate_pad_numbers_are_jumpers no)
		(fp_line
			(start 0 -1.27)
			(end 0 -0.635)
			(stroke
				(width 0.1524)
				(type default)
			)
			(layer "B.SilkS")
		)
		(fp_line
			(start -2.54 -1.27)
			(end 0 -1.27)
			(stroke
				(width 0.1524)
				(type default)
			)
			(layer "B.SilkS")
		)
		(fp_line
			(start -2.54 -1.1303)
			(end -2.54 -1.27)
			(stroke
				(width 0.1524)
				(type default)
			)
			(layer "B.SilkS")
		)
		(fp_line
			(start 0 0.635)
			(end 0 1.905)
			(stroke
				(width 0.1524)
				(type default)
			)
			(layer "B.SilkS")
		)
		(fp_line
			(start -2.54 1.4097)
			(end -2.54 1.1303)
			(stroke
				(width 0.1524)
				(type default)
			)
			(layer "B.SilkS")
		)
		(fp_line
			(start 0 3.175)
			(end 0 3.81)
			(stroke
				(width 0.1524)
				(type default)
			)
			(layer "B.SilkS")
		)
		(fp_line
			(start 0 3.81)
			(end -2.54 3.81)
			(stroke
				(width 0.1524)
				(type default)
			)
			(layer "B.SilkS")
		)
		(fp_line
			(start -2.54 3.81)
			(end -2.54 3.6703)
			(stroke
				(width 0.1524)
				(type default)
			)
			(layer "B.SilkS")
		)
		(fp_poly
			(pts
				(xy 2.917444 -0.951484) (xy 2.917444 0.572516) (xy 1.393444 -0.189484)
			)
			(stroke
				(width 0)
				(type default)
			)
			(fill yes)
			(layer "B.SilkS")
		)
		(fp_line
			(start 0 -1.27)
			(end 0 3.81)
			(stroke
				(width 0.1)
				(type default)
			)
			(layer "B.Fab")
		)
		(fp_line
			(start -2.54 -1.27)
			(end 0 -1.27)
			(stroke
				(width 0.1)
				(type default)
			)
			(layer "B.Fab")
		)
		(fp_line
			(start 0 3.81)
			(end -2.54 3.81)
			(stroke
				(width 0.1)
				(type default)
			)
			(layer "B.Fab")
		)
		(fp_line
			(start -2.54 3.81)
			(end -2.54 -1.27)
			(stroke
				(width 0.1)
				(type default)
			)
			(layer "B.Fab")
		)
		(fp_poly
			(pts
				(xy 0.761746 0) (xy 2.285746 -0.762) (xy 2.285746 0.762)
			)
			(stroke
				(width 0)
				(type default)
			)
			(fill yes)
			(layer "B.Fab")
		)
		(pad "1" thru_hole circle
			(at 0 0 270)
			(size 1.0033 1.0033)
			(drill 0.249936)
			(layers "*.Cu" "*.Mask")
			(remove_unused_layers no)
			(net "TDR_DIFF_85_IN5_DP")
			(clearance 0.10795)
			(padstack
				(mode front_inner_back)
				(layer "Inner"
					(shape circle)
					(size 0.8001 0.8001)
					(clearance 0.1524)
				)
				(layer "B.Cu"
					(shape circle)
					(size 1.0033 1.0033)
					(thermal_gap 0.10795)
					(clearance 0.10795)
				)
			)
		)
		(pad "2" thru_hole circle
			(at -2.54 0 270)
			(size 1.9939 1.9939)
			(drill 0.249936)
			(layers "*.Cu" "*.Mask")
			(remove_unused_layers no)
			(net "T1_GND")
			(clearance 0.10795)
			(padstack
				(mode front_inner_back)
				(layer "Inner"
					(shape circle)
					(size 0.8001 0.8001)
					(clearance 0.1524)
				)
				(layer "B.Cu"
					(shape circle)
					(size 1.9939 1.9939)
					(thermal_gap 0.10795)
					(clearance 0.10795)
				)
			)
		)
		(pad "3" thru_hole circle
			(at -2.54 2.54 270)
			(size 1.9939 1.9939)
			(drill 0.249936)
			(layers "*.Cu" "*.Mask")
			(remove_unused_layers no)
			(net "T1_GND")
			(clearance 0.10795)
			(padstack
				(mode front_inner_back)
				(layer "Inner"
					(shape circle)
					(size 0.8001 0.8001)
					(clearance 0.1524)
				)
				(layer "B.Cu"
					(shape circle)
					(size 1.9939 1.9939)
					(thermal_gap 0.10795)
					(clearance 0.10795)
				)
			)
		)
		(pad "4" thru_hole circle
			(at 0 2.54 270)
			(size 1.0033 1.0033)
			(drill 0.249936)
			(layers "*.Cu" "*.Mask")
			(remove_unused_layers no)
			(net "TDR_DIFF_85_IN5_DN")
			(clearance 0.10795)
			(padstack
				(mode front_inner_back)
				(layer "Inner"
					(shape circle)
					(size 0.8001 0.8001)
					(clearance 0.1524)
				)
				(layer "B.Cu"
					(shape circle)
					(size 1.0033 1.0033)
					(thermal_gap 0.10795)
					(clearance 0.10795)
				)
			)
		)
	)
	(footprint ""
		(layer "B.Cu")
		(at 123.57862 -27.424888)
		(property "Reference" "C2292"
			(at 0 0 0)
			(layer "B.SilkS")
			(hide yes)
			(effects
				(font
					(size 1.27 1.27)
				)
				(justify mirror)
			)
		)
		(property "Value" ""
			(at 0 0 0)
			(layer "B.Fab")
			(effects
				(font
					(size 1.27 1.27)
				)
				(justify mirror)
			)
		)
		(duplicate_pad_numbers_are_jumpers no)
		(fp_line
			(start -0.299974 -0.150114)
			(end -0.299974 0.150114)
			(stroke
				(width 0.1)
				(type default)
			)
			(layer "B.Fab")
		)
		(fp_line
			(start -0.299974 0.150114)
			(end 0.299974 0.150114)
			(stroke
				(width 0.1)
				(type default)
			)
			(layer "B.Fab")
		)
		(fp_line
			(start 0.299974 -0.150114)
			(end -0.299974 -0.150114)
			(stroke
				(width 0.1)
				(type default)
			)
			(layer "B.Fab")
		)
		(fp_line
			(start 0.299974 0.150114)
			(end 0.299974 -0.150114)
			(stroke
				(width 0.1)
				(type default)
			)
			(layer "B.Fab")
		)
		(pad "1" smd rect
			(at 0.2667 0 180)
			(size 0.3048 0.381)
			(layers "B.Cu" "B.Mask" "B.Paste")
			(net "USB3_PCH_RX_BUF_C_DN<4>")
		)
		(pad "2" smd rect
			(at -0.2667 0 180)
			(size 0.3048 0.381)
			(layers "B.Cu" "B.Mask" "B.Paste")
			(net "USB3_PCH_RX_BUF_DN<4>")
		)
	)
	(footprint ""
		(layer "B.Cu")
		(at 160.83788 -121.376948)
		(property "Reference" "R987"
			(at 0 0 0)
			(layer "B.SilkS")
			(hide yes)
			(effects
				(font
					(size 1.27 1.27)
				)
				(justify mirror)
			)
		)
		(property "Value" ""
			(at 0 0 0)
			(layer "B.Fab")
			(effects
				(font
					(size 1.27 1.27)
				)
				(justify mirror)
			)
		)
		(duplicate_pad_numbers_are_jumpers no)
		(fp_line
			(start -0.7874 -0.4064)
			(end -0.7874 0.4064)
			(stroke
				(width 0.1524)
				(type default)
			)
			(layer "B.SilkS")
		)
		(fp_line
			(start -0.7874 0.4064)
			(end 0.7874 0.4064)
			(stroke
				(width 0.1524)
				(type default)
			)
			(layer "B.SilkS")
		)
		(fp_line
			(start 0.7874 -0.4064)
			(end -0.7874 -0.4064)
			(stroke
				(width 0.1524)
				(type default)
			)
			(layer "B.SilkS")
		)
		(fp_line
			(start 0.7874 0.4064)
			(end 0.7874 -0.4064)
			(stroke
				(width 0.1524)
				(type default)
			)
			(layer "B.SilkS")
		)
		(fp_line
			(start -0.67945 -0.3048)
			(end -0.67945 0.3048)
			(stroke
				(width 0.1)
				(type default)
			)
			(layer "B.Fab")
		)
		(fp_line
			(start -0.67945 0.3048)
			(end -0.120396 0.3048)
			(stroke
				(width 0.1)
				(type default)
			)
			(layer "B.Fab")
		)
		(fp_line
			(start -0.12065 -0.3048)
			(end -0.67945 -0.3048)
			(stroke
				(width 0.1)
				(type default)
			)
			(layer "B.Fab")
		)
		(fp_line
			(start -0.12065 -0.2794)
			(end -0.12065 -0.3048)
			(stroke
				(width 0.1)
				(type default)
			)
			(layer "B.Fab")
		)
		(fp_line
			(start -0.120396 0.2794)
			(end 0.12065 0.2794)
			(stroke
				(width 0.1)
				(type default)
			)
			(layer "B.Fab")
		)
		(fp_line
			(start -0.120396 0.3048)
			(end -0.120396 0.2794)
			(stroke
				(width 0.1)
				(type default)
			)
			(layer "B.Fab")
		)
		(fp_line
			(start 0.12065 -0.305054)
			(end 0.12065 -0.2794)
			(stroke
				(width 0.1)
				(type default)
			)
			(layer "B.Fab")
		)
		(fp_line
			(start 0.12065 -0.2794)
			(end -0.12065 -0.2794)
			(stroke
				(width 0.1)
				(type default)
			)
			(layer "B.Fab")
		)
		(fp_line
			(start 0.12065 0.2794)
			(end 0.12065 0.3048)
			(stroke
				(width 0.1)
				(type default)
			)
			(layer "B.Fab")
		)
		(fp_line
			(start 0.12065 0.3048)
			(end 0.67945 0.3048)
			(stroke
				(width 0.1)
				(type default)
			)
			(layer "B.Fab")
		)
		(fp_line
			(start 0.67945 -0.305054)
			(end 0.12065 -0.305054)
			(stroke
				(width 0.1)
				(type default)
			)
			(layer "B.Fab")
		)
		(fp_line
			(start 0.67945 0.3048)
			(end 0.67945 -0.305054)
			(stroke
				(width 0.1)
				(type default)
			)
			(layer "B.Fab")
		)
		(pad "1" smd circle
			(at 0.40005 0 180)
			(size 0 0)
			(layers "B.Cu" "B.Mask" "B.Paste")
			(net "FM_PVCCINFAON_CPU1_R_EN")
		)
		(pad "2" smd circle
			(at -0.40005 0 180)
			(size 0 0)
			(layers "B.Cu" "B.Mask" "B.Paste")
			(net "FM_PVCCINFAON_CPU1_EN")
		)
	)
	(footprint ""
		(layer "B.Cu")
		(at 261.375906 -104.832912 180)
		(property "Reference" "R447"
			(at 0 0 0)
			(layer "B.SilkS")
			(hide yes)
			(effects
				(font
					(size 1.27 1.27)
				)
				(justify mirror)
			)
		)
		(property "Value" ""
			(at 0 0 0)
			(layer "B.Fab")
			(effects
				(font
					(size 1.27 1.27)
				)
				(justify mirror)
			)
		)
		(duplicate_pad_numbers_are_jumpers no)
		(fp_line
			(start 1.2954 0.5842)
			(end 1.2954 -0.5842)
			(stroke
				(width 0.1524)
				(type default)
			)
			(layer "B.SilkS")
		)
		(fp_line
			(start 1.2954 -0.5842)
			(end -1.2954 -0.5842)
			(stroke
				(width 0.1524)
				(type default)
			)
			(layer "B.SilkS")
		)
		(fp_line
			(start -1.2954 0.5842)
			(end 1.2954 0.5842)
			(stroke
				(width 0.1524)
				(type default)
			)
			(layer "B.SilkS")
		)
		(fp_line
			(start -1.2954 -0.5842)
			(end -1.2954 0.5842)
			(stroke
				(width 0.1524)
				(type default)
			)
			(layer "B.SilkS")
		)
		(fp_line
			(start 1.1938 0.4064)
			(end 1.1938 -0.406654)
			(stroke
				(width 0.1)
				(type default)
			)
			(layer "B.Fab")
		)
		(fp_line
			(start 1.1938 -0.406654)
			(end 0.8636 -0.406654)
			(stroke
				(width 0.1)
				(type default)
			)
			(layer "B.Fab")
		)
		(fp_line
			(start 0.8636 0.4572)
			(end 0.8636 0.4318)
			(stroke
				(width 0.1)
				(type default)
			)
			(layer "B.Fab")
		)
		(fp_line
			(start 0.8636 0.4318)
			(end 0.8636 0.4064)
			(stroke
				(width 0.1)
				(type default)
			)
			(layer "B.Fab")
		)
		(fp_line
			(start 0.8636 0.4064)
			(end 1.1938 0.4064)
			(stroke
				(width 0.1)
				(type default)
			)
			(layer "B.Fab")
		)
		(fp_line
			(start 0.8636 -0.406654)
			(end 0.8636 -0.4572)
			(stroke
				(width 0.1)
				(type default)
			)
			(layer "B.Fab")
		)
		(fp_line
			(start 0.8636 -0.4572)
			(end -0.8636 -0.4572)
			(stroke
				(width 0.1)
				(type default)
			)
			(layer "B.Fab")
		)
		(fp_line
			(start -0.8636 0.4572)
			(end 0.8636 0.4572)
			(stroke
				(width 0.1)
				(type default)
			)
			(layer "B.Fab")
		)
		(fp_line
			(start -0.8636 0.4064)
			(end -0.8636 0.4572)
			(stroke
				(width 0.1)
				(type default)
			)
			(layer "B.Fab")
		)
		(fp_line
			(start -0.8636 -0.406654)
			(end -1.1938 -0.406654)
			(stroke
				(width 0.1)
				(type default)
			)
			(layer "B.Fab")
		)
		(fp_line
			(start -0.8636 -0.4572)
			(end -0.8636 -0.406654)
			(stroke
				(width 0.1)
				(type default)
			)
			(layer "B.Fab")
		)
		(fp_line
			(start -1.1938 0.4064)
			(end -0.8636 0.4064)
			(stroke
				(width 0.1)
				(type default)
			)
			(layer "B.Fab")
		)
		(fp_line
			(start -1.1938 -0.406654)
			(end -1.1938 0.4064)
			(stroke
				(width 0.1)
				(type default)
			)
			(layer "B.Fab")
		)
		(pad "1" smd rect
			(at 0.7366 0 90)
			(size 0.7112 0.8128)
			(layers "B.Cu" "B.Mask" "B.Paste")
			(net "P3V3_AUX_CLK_GEN_VDDMXCK_CK440")
		)
		(pad "2" smd rect
			(at -0.7366 0 90)
			(size 0.7112 0.8128)
			(layers "B.Cu" "B.Mask" "B.Paste")
			(net "P3V3_AUX_CLK_GEN_VDDPT_CK440")
		)
	)
)
